# TIMECARD (Time Appliance Project (Time Card)) — schematic netlist excerpt (pin names and nets, part order shuffled) for the footprints in the layout excerpt that follows; sources: Cadence DE-HDL packaged netlist, KiCad conversion of R4006-B0001-02_R01.brd

R427  RESISTOR  100OHM 1%  pkg SMC_0402R_H016  page 26 : \1\ = FPGA_OUT_GPS_LED_RED_N ; \2\ = UNNAMED_14_LED4PV14_I269_3
R361  RESISTOR  4.7KOHM 1%  pkg SMC_0402R_H016  page 23 : \1\ = XP3R3V_FPGA ; \2\ = SMA1_SIG_OUT_BF_EN_N

(kicad_pcb
	(version 20260206)
	(generator "pcbnew")
	(generator_version "10.0")
	(general
		(thickness 1.6)
		(legacy_teardrops no)
	)
	(paper "A4")
	(title_block
		(title "timecard-production-celestica-r4006 — R4006-B0001-02_R01.brd")
		(comment 1 "Time Appliance Project (Time Card) / footprints 517-518 of 1113")
	)
	(layers
		(0 "F.Cu" signal "TOP")
		(4 "In1.Cu" signal "L02_GND1")
		(6 "In2.Cu" signal "L03_SIG1")
		(8 "In3.Cu" signal "L04_GND2")
		(10 "In4.Cu" signal "L05_VCC1")
		(12 "In5.Cu" signal "L06_VCC2")
		(14 "In6.Cu" signal "L07_GND3")
		(16 "In7.Cu" signal "L08_SIG2")
		(18 "In8.Cu" signal "L09_GND4")
		(2 "B.Cu" signal "BOTTOM")
		(9 "F.Adhes" user "F.Adhesive")
		(11 "B.Adhes" user "B.Adhesive")
		(13 "F.Paste" user "Package Geometry/Pastemask Top")
		(15 "B.Paste" user "Package Geometry/Pastemask Bottom")
		(5 "F.SilkS" user "Ref Des/Silkscreen Top")
		(7 "B.SilkS" user "Ref Des/Silkscreen Bottom")
		(1 "F.Mask" user "Board Geometry/Soldermask Top")
		(3 "B.Mask" user "Board Geometry/Soldermask Bottom")
		(17 "Dwgs.User" user "User.Drawings")
		(19 "Cmts.User" user "User.Comments")
		(21 "Eco1.User" user "User.Eco1")
		(23 "Eco2.User" user "User.Eco2")
		(25 "Edge.Cuts" user "Board Geometry/Outline")
		(27 "Margin" user)
		(31 "F.CrtYd" user "Package Geometry/Place Bound Top")
		(29 "B.CrtYd" user "Package Geometry/Place Bound Bottom")
		(35 "F.Fab" user "Ref Des/Assembly Top")
		(33 "B.Fab" user "Ref Des/Assembly Bottom")
	)
	(footprint ""
		(layer "F.Cu")
		(at 14.6812 -65.786 -90)
		(property "Reference" "R361"
			(at -5.334 0.41783 90)
			(unlocked yes)
			(layer "F.SilkS")
			(effects
				(font
					(size 0.7874 0.5842)
					(thickness 0.1524)
				)
			)
		)
		(property "Value" "VAL*"
			(at 0.02032 2.13233 270)
			(unlocked yes)
			(layer "F.Fab")
			(hide yes)
			(effects
				(font
					(size 0.7874 0.5842)
					(thickness 0.1524)
				)
			)
		)
		(property "Device Type" "RESISTOR-G155-14701-01,4.7KOHMA"
			(at 0.008382 1.210564 270)
			(unlocked yes)
			(layer "F.Fab")
			(hide yes)
			(effects
				(font
					(size 0.7874 0.5842)
					(thickness 0.1524)
				)
			)
		)
		(property "User Part Number" "PARTNUM*"
			(at 0.02032 4.024884 270)
			(unlocked yes)
			(layer "Cmts.User")
			(hide yes)
			(effects
				(font
					(size 0.7874 0.5842)
					(thickness 0.1524)
				)
			)
		)
		(property "Tolerance" "TOL*"
			(at 0.044704 3.05435 270)
			(unlocked yes)
			(layer "Cmts.User")
			(hide yes)
			(effects
				(font
					(size 0.7874 0.5842)
					(thickness 0.1524)
				)
			)
		)
		(duplicate_pad_numbers_are_jumpers no)
		(fp_line
			(start -1.143 0.5588)
			(end 1.143 0.5588)
			(stroke
				(width 0.1)
				(type default)
			)
			(layer "F.SilkS")
		)
		(fp_line
			(start 1.143 0.5588)
			(end 1.143 -0.5588)
			(stroke
				(width 0.1)
				(type default)
			)
			(layer "F.SilkS")
		)
		(fp_line
			(start -1.143 -0.5588)
			(end -1.143 0.5588)
			(stroke
				(width 0.1)
				(type default)
			)
			(layer "F.SilkS")
		)
		(fp_line
			(start 1.143 -0.5588)
			(end -1.143 -0.5588)
			(stroke
				(width 0.1)
				(type default)
			)
			(layer "F.SilkS")
		)
		(fp_rect
			(start -1.143 -0.5588)
			(end 1.143 0.5588)
			(stroke
				(width 0)
				(type default)
			)
			(fill no)
			(layer "F.CrtYd")
		)
		(fp_line
			(start -0.508 0.3048)
			(end 0.508 0.3048)
			(stroke
				(width 0.1)
				(type default)
			)
			(layer "F.Fab")
		)
		(fp_line
			(start 0.508 0.3048)
			(end 0.508 -0.3048)
			(stroke
				(width 0.1)
				(type default)
			)
			(layer "F.Fab")
		)
		(fp_line
			(start -0.508 -0.3048)
			(end -0.508 0.3048)
			(stroke
				(width 0.1)
				(type default)
			)
			(layer "F.Fab")
		)
		(fp_line
			(start 0.508 -0.3048)
			(end -0.508 -0.3048)
			(stroke
				(width 0.1)
				(type default)
			)
			(layer "F.Fab")
		)
		(pad "1" smd rect
			(at -0.5334 0 270)
			(size 0.7112 0.6096)
			(layers "F.Cu" "F.Mask" "F.Paste")
			(net "XP3R3V_FPGA")
		)
		(pad "2" smd rect
			(at 0.5334 0 270)
			(size 0.7112 0.6096)
			(layers "F.Cu" "F.Mask" "F.Paste")
			(net "SMA1_SIG_OUT_BF_EN_N")
		)
		(zone
			(layer "F.Cu")
			(hatch none 0.5)
			(connect_pads
				(clearance 0)
			)
			(min_thickness 0.25)
			(keepout
				(tracks not_allowed)
				(vias allowed)
				(pads allowed)
				(copperpour not_allowed)
				(footprints allowed)
			)
			(placement
				(enabled no)
				(sheetname "")
			)
			(fill
				(thermal_gap 0.5)
				(thermal_bridge_width 0.5)
				(island_removal_mode 0)
			)
			(polygon
				(pts
					(xy 14.986 -65.8622) (xy 14.3764 -65.8622) (xy 14.3764 -65.7098) (xy 14.986 -65.7098)
				)
			)
		)
		(zone
			(layer "F.Cu")
			(hatch none 0.5)
			(connect_pads
				(clearance 0)
			)
			(min_thickness 0.25)
			(keepout
				(tracks allowed)
				(vias not_allowed)
				(pads allowed)
				(copperpour not_allowed)
				(footprints allowed)
			)
			(placement
				(enabled no)
				(sheetname "")
			)
			(fill
				(thermal_gap 0.5)
				(thermal_bridge_width 0.5)
				(island_removal_mode 0)
			)
			(polygon
				(pts
					(xy 14.986 -65.8622) (xy 14.3764 -65.8622) (xy 14.3764 -65.7098) (xy 14.986 -65.7098)
				)
			)
		)
	)
	(footprint ""
		(layer "F.Cu")
		(at 7.112 -81.534 90)
		(property "Reference" "R427"
			(at -2.667 -0.34163 90)
			(unlocked yes)
			(layer "F.SilkS")
			(effects
				(font
					(size 0.7874 0.5842)
					(thickness 0.1524)
				)
			)
		)
		(property "Value" "VAL*"
			(at 0.02032 2.13233 90)
			(unlocked yes)
			(layer "F.Fab")
			(hide yes)
			(effects
				(font
					(size 0.7874 0.5842)
					(thickness 0.1524)
				)
			)
		)
		(property "Device Type" "RESISTOR-G155-11000-01,100OHM,A"
			(at 0.008382 1.210564 90)
			(unlocked yes)
			(layer "F.Fab")
			(hide yes)
			(effects
				(font
					(size 0.7874 0.5842)
					(thickness 0.1524)
				)
			)
		)
		(property "User Part Number" "PARTNUM*"
			(at 0.02032 4.024884 90)
			(unlocked yes)
			(layer "Cmts.User")
			(hide yes)
			(effects
				(font
					(size 0.7874 0.5842)
					(thickness 0.1524)
				)
			)
		)
		(property "Tolerance" "TOL*"
			(at 0.044704 3.05435 90)
			(unlocked yes)
			(layer "Cmts.User")
			(hide yes)
			(effects
				(font
					(size 0.7874 0.5842)
					(thickness 0.1524)
				)
			)
		)
		(duplicate_pad_numbers_are_jumpers no)
		(fp_line
			(start 1.143 -0.5588)
			(end -1.143 -0.5588)
			(stroke
				(width 0.1)
				(type default)
			)
			(layer "F.SilkS")
		)
		(fp_line
			(start -1.143 -0.5588)
			(end -1.143 0.5588)
			(stroke
				(width 0.1)
				(type default)
			)
			(layer "F.SilkS")
		)
		(fp_line
			(start 1.143 0.5588)
			(end 1.143 -0.5588)
			(stroke
				(width 0.1)
				(type default)
			)
			(layer "F.SilkS")
		)
		(fp_line
			(start -1.143 0.5588)
			(end 1.143 0.5588)
			(stroke
				(width 0.1)
				(type default)
			)
			(layer "F.SilkS")
		)
		(fp_poly
			(pts
				(xy -1.143 0.5588) (xy 1.143 0.5588) (xy 1.143 -0.5588) (xy -1.143 -0.5588)
			)
			(stroke
				(width 0)
				(type default)
			)
			(fill no)
			(layer "F.CrtYd")
		)
		(fp_line
			(start 0.508 -0.3048)
			(end -0.508 -0.3048)
			(stroke
				(width 0.1)
				(type default)
			)
			(layer "F.Fab")
		)
		(fp_line
			(start -0.508 -0.3048)
			(end -0.508 0.3048)
			(stroke
				(width 0.1)
				(type default)
			)
			(layer "F.Fab")
		)
		(fp_line
			(start 0.508 0.3048)
			(end 0.508 -0.3048)
			(stroke
				(width 0.1)
				(type default)
			)
			(layer "F.Fab")
		)
		(fp_line
			(start -0.508 0.3048)
			(end 0.508 0.3048)
			(stroke
				(width 0.1)
				(type default)
			)
			(layer "F.Fab")
		)
		(pad "1" smd rect
			(at -0.5334 0 90)
			(size 0.7112 0.6096)
			(layers "F.Cu" "F.Mask" "F.Paste")
			(net "FPGA_OUT_GPS_LED_RED_N")
		)
		(pad "2" smd rect
			(at 0.5334 0 90)
			(size 0.7112 0.6096)
			(layers "F.Cu" "F.Mask" "F.Paste")
			(net "UNNAMED_14_LED4PV14_I269_3")
		)
		(zone
			(layer "F.Cu")
			(hatch none 0.5)
			(connect_pads
				(clearance 0)
			)
			(min_thickness 0.25)
			(keepout
				(tracks not_allowed)
				(vias allowed)
				(pads allowed)
				(copperpour not_allowed)
				(footprints allowed)
			)
			(placement
				(enabled no)
				(sheetname "")
			)
			(fill
				(thermal_gap 0.5)
				(thermal_bridge_width 0.5)
				(island_removal_mode 0)
			)
			(polygon
				(pts
					(xy 7.4168 -81.4578) (xy 7.4168 -81.6102) (xy 6.8072 -81.6102) (xy 6.8072 -81.4578)
				)
			)
		)
		(zone
			(layer "F.Cu")
			(hatch none 0.5)
			(connect_pads
				(clearance 0)
			)
			(min_thickness 0.25)
			(keepout
				(tracks allowed)
				(vias not_allowed)
				(pads allowed)
				(copperpour not_allowed)
				(footprints allowed)
			)
			(placement
				(enabled no)
				(sheetname "")
			)
			(fill
				(thermal_gap 0.5)
				(thermal_bridge_width 0.5)
				(island_removal_mode 0)
			)
			(polygon
				(pts
					(xy 7.4168 -81.4578) (xy 7.4168 -81.6102) (xy 6.8072 -81.6102) (xy 6.8072 -81.4578)
				)
			)
		)
	)
)
